(kicad_pcb
	(version 20260206)
	(generator "pcbnew")
	(generator_version "10.0")
	(general
		(thickness 1.6)
		(legacy_teardrops no)
	)
	(paper "A4")
	(title_block
		(title "03242023_DA0F0TMBIJ0_F0T_Motherboard_J_brd_V01_OCP.brd")
		(comment 1 "Grand Teton / footprints 5046-5051 of 6105")
	)
	(layers
		(0 "F.Cu" signal "TOP")
		(4 "In1.Cu" signal "GND")
		(6 "In2.Cu" signal "IN1")
		(8 "In3.Cu" signal "GND1")
		(10 "In4.Cu" signal "IN2")
		(12 "In5.Cu" signal "GND2")
		(14 "In6.Cu" signal "IN3")
		(16 "In7.Cu" signal "GND3")
		(18 "In8.Cu" signal "VCC")
		(20 "In9.Cu" signal "VCC1")
		(22 "In10.Cu" signal "GND4")
		(24 "In11.Cu" signal "IN4")
		(26 "In12.Cu" signal "GND5")
		(28 "In13.Cu" signal "IN5")
		(30 "In14.Cu" signal "GND6")
		(32 "In15.Cu" signal "IN6")
		(34 "In16.Cu" signal "GND7")
		(2 "B.Cu" signal "BOTTOM")
		(9 "F.Adhes" user "F.Adhesive")
		(11 "B.Adhes" user "B.Adhesive")
		(13 "F.Paste" user "Package Geometry/Pastemask Top")
		(15 "B.Paste" user "Package Geometry/Pastemask Bottom")
		(5 "F.SilkS" user "Ref Des/Silkscreen Top")
		(7 "B.SilkS" user "Ref Des/Silkscreen Bottom")
		(1 "F.Mask" user "Board Geometry/Soldermask Top")
		(3 "B.Mask" user "Board Geometry/Soldermask Bottom")
		(17 "Dwgs.User" user "User.Drawings")
		(19 "Cmts.User" user "User.Comments")
		(21 "Eco1.User" user "User.Eco1")
		(23 "Eco2.User" user "User.Eco2")
		(25 "Edge.Cuts" user "Board Geometry/Outline")
		(27 "Margin" user)
		(31 "F.CrtYd" user "Package Geometry/Place Bound Top")
		(29 "B.CrtYd" user "Package Geometry/Place Bound Bottom")
		(35 "F.Fab" user "Ref Des/Assembly Top")
		(33 "B.Fab" user "Ref Des/Assembly Bottom")
	)
	(footprint ""
		(layer "B.Cu")
		(at 182.68188 -103.723948)
		(property "Reference" "C1842"
			(at 0 0 0)
			(layer "B.SilkS")
			(hide yes)
			(effects
				(font
					(size 1.27 1.27)
				)
				(justify mirror)
			)
		)
		(property "Value" ""
			(at 0 0 0)
			(layer "B.Fab")
			(effects
				(font
					(size 1.27 1.27)
				)
				(justify mirror)
			)
		)
		(duplicate_pad_numbers_are_jumpers no)
		(fp_line
			(start -0.7874 -0.4064)
			(end -0.7874 0.4064)
			(stroke
				(width 0.1524)
				(type default)
			)
			(layer "B.SilkS")
		)
		(fp_line
			(start -0.7874 0.4064)
			(end 0.7874 0.4064)
			(stroke
				(width 0.1524)
				(type default)
			)
			(layer "B.SilkS")
		)
		(fp_line
			(start 0.7874 -0.4064)
			(end -0.7874 -0.4064)
			(stroke
				(width 0.1524)
				(type default)
			)
			(layer "B.SilkS")
		)
		(fp_line
			(start 0.7874 0.4064)
			(end 0.7874 -0.4064)
			(stroke
				(width 0.1524)
				(type default)
			)
			(layer "B.SilkS")
		)
		(fp_line
			(start -0.67945 -0.3048)
			(end -0.67945 0.3048)
			(stroke
				(width 0.1)
				(type default)
			)
			(layer "B.Fab")
		)
		(fp_line
			(start -0.67945 0.3048)
			(end -0.120396 0.3048)
			(stroke
				(width 0.1)
				(type default)
			)
			(layer "B.Fab")
		)
		(fp_line
			(start -0.12065 -0.3048)
			(end -0.67945 -0.3048)
			(stroke
				(width 0.1)
				(type default)
			)
			(layer "B.Fab")
		)
		(fp_line
			(start -0.12065 -0.2794)
			(end -0.12065 -0.3048)
			(stroke
				(width 0.1)
				(type default)
			)
			(layer "B.Fab")
		)
		(fp_line
			(start -0.120396 0.2794)
			(end 0.12065 0.2794)
			(stroke
				(width 0.1)
				(type default)
			)
			(layer "B.Fab")
		)
		(fp_line
			(start -0.120396 0.3048)
			(end -0.120396 0.2794)
			(stroke
				(width 0.1)
				(type default)
			)
			(layer "B.Fab")
		)
		(fp_line
			(start 0.12065 -0.305054)
			(end 0.12065 -0.2794)
			(stroke
				(width 0.1)
				(type default)
			)
			(layer "B.Fab")
		)
		(fp_line
			(start 0.12065 -0.2794)
			(end -0.12065 -0.2794)
			(stroke
				(width 0.1)
				(type default)
			)
			(layer "B.Fab")
		)
		(fp_line
			(start 0.12065 0.2794)
			(end 0.12065 0.3048)
			(stroke
				(width 0.1)
				(type default)
			)
			(layer "B.Fab")
		)
		(fp_line
			(start 0.12065 0.3048)
			(end 0.67945 0.3048)
			(stroke
				(width 0.1)
				(type default)
			)
			(layer "B.Fab")
		)
		(fp_line
			(start 0.67945 -0.305054)
			(end 0.12065 -0.305054)
			(stroke
				(width 0.1)
				(type default)
			)
			(layer "B.Fab")
		)
		(fp_line
			(start 0.67945 0.3048)
			(end 0.67945 -0.305054)
			(stroke
				(width 0.1)
				(type default)
			)
			(layer "B.Fab")
		)
		(pad "1" smd circle
			(at 0.40005 0 180)
			(size 0 0)
			(layers "B.Cu" "B.Mask" "B.Paste")
			(net "P3V3_AUX_FPGA_VCCIO3")
		)
		(pad "2" smd circle
			(at -0.40005 0 180)
			(size 0 0)
			(layers "B.Cu" "B.Mask" "B.Paste")
			(net "GND")
		)
	)
	(footprint ""
		(layer "B.Cu")
		(at 232.692194 -129.673858 -90)
		(property "Reference" "C205"
			(at 0 0 90)
			(layer "B.SilkS")
			(hide yes)
			(effects
				(font
					(size 1.27 1.27)
				)
				(justify mirror)
			)
		)
		(property "Value" ""
			(at 0 0 90)
			(layer "B.Fab")
			(effects
				(font
					(size 1.27 1.27)
				)
				(justify mirror)
			)
		)
		(duplicate_pad_numbers_are_jumpers no)
		(fp_line
			(start -0.7874 0.4064)
			(end 0.7874 0.4064)
			(stroke
				(width 0.1524)
				(type default)
			)
			(layer "B.SilkS")
		)
		(fp_line
			(start 0.7874 0.4064)
			(end 0.7874 -0.4064)
			(stroke
				(width 0.1524)
				(type default)
			)
			(layer "B.SilkS")
		)
		(fp_line
			(start -0.7874 -0.4064)
			(end -0.7874 0.4064)
			(stroke
				(width 0.1524)
				(type default)
			)
			(layer "B.SilkS")
		)
		(fp_line
			(start 0.7874 -0.4064)
			(end -0.7874 -0.4064)
			(stroke
				(width 0.1524)
				(type default)
			)
			(layer "B.SilkS")
		)
		(fp_line
			(start -0.67945 0.3048)
			(end -0.120396 0.3048)
			(stroke
				(width 0.1)
				(type default)
			)
			(layer "B.Fab")
		)
		(fp_line
			(start -0.120396 0.3048)
			(end -0.120396 0.2794)
			(stroke
				(width 0.1)
				(type default)
			)
			(layer "B.Fab")
		)
		(fp_line
			(start 0.12065 0.3048)
			(end 0.67945 0.3048)
			(stroke
				(width 0.1)
				(type default)
			)
			(layer "B.Fab")
		)
		(fp_line
			(start 0.67945 0.3048)
			(end 0.67945 -0.305054)
			(stroke
				(width 0.1)
				(type default)
			)
			(layer "B.Fab")
		)
		(fp_line
			(start -0.120396 0.2794)
			(end 0.12065 0.2794)
			(stroke
				(width 0.1)
				(type default)
			)
			(layer "B.Fab")
		)
		(fp_line
			(start 0.12065 0.2794)
			(end 0.12065 0.3048)
			(stroke
				(width 0.1)
				(type default)
			)
			(layer "B.Fab")
		)
		(fp_line
			(start -0.12065 -0.2794)
			(end -0.12065 -0.3048)
			(stroke
				(width 0.1)
				(type default)
			)
			(layer "B.Fab")
		)
		(fp_line
			(start 0.12065 -0.2794)
			(end -0.12065 -0.2794)
			(stroke
				(width 0.1)
				(type default)
			)
			(layer "B.Fab")
		)
		(fp_line
			(start -0.67945 -0.3048)
			(end -0.67945 0.3048)
			(stroke
				(width 0.1)
				(type default)
			)
			(layer "B.Fab")
		)
		(fp_line
			(start -0.12065 -0.3048)
			(end -0.67945 -0.3048)
			(stroke
				(width 0.1)
				(type default)
			)
			(layer "B.Fab")
		)
		(fp_line
			(start 0.12065 -0.305054)
			(end 0.12065 -0.2794)
			(stroke
				(width 0.1)
				(type default)
			)
			(layer "B.Fab")
		)
		(fp_line
			(start 0.67945 -0.305054)
			(end 0.12065 -0.305054)
			(stroke
				(width 0.1)
				(type default)
			)
			(layer "B.Fab")
		)
		(pad "1" smd circle
			(at 0.40005 0 90)
			(size 0 0)
			(layers "B.Cu" "B.Mask" "B.Paste")
			(net "P3V3_DB2000_VDD")
		)
		(pad "2" smd circle
			(at -0.40005 0 90)
			(size 0 0)
			(layers "B.Cu" "B.Mask" "B.Paste")
			(net "GND")
		)
	)
	(footprint ""
		(layer "B.Cu")
		(at 184.010808 -402.721572 -90)
		(property "Reference" "PC2186"
			(at 0 0 90)
			(layer "B.SilkS")
			(hide yes)
			(effects
				(font
					(size 1.27 1.27)
				)
				(justify mirror)
			)
		)
		(property "Value" ""
			(at 0 0 90)
			(layer "B.Fab")
			(effects
				(font
					(size 1.27 1.27)
				)
				(justify mirror)
			)
		)
		(duplicate_pad_numbers_are_jumpers no)
		(fp_line
			(start -0.7874 0.4064)
			(end 0.7874 0.4064)
			(stroke
				(width 0.1524)
				(type default)
			)
			(layer "B.SilkS")
		)
		(fp_line
			(start 0.7874 0.4064)
			(end 0.7874 -0.4064)
			(stroke
				(width 0.1524)
				(type default)
			)
			(layer "B.SilkS")
		)
		(fp_line
			(start -0.7874 -0.4064)
			(end -0.7874 0.4064)
			(stroke
				(width 0.1524)
				(type default)
			)
			(layer "B.SilkS")
		)
		(fp_line
			(start 0.7874 -0.4064)
			(end -0.7874 -0.4064)
			(stroke
				(width 0.1524)
				(type default)
			)
			(layer "B.SilkS")
		)
		(fp_line
			(start -0.67945 0.3048)
			(end -0.120396 0.3048)
			(stroke
				(width 0.1)
				(type default)
			)
			(layer "B.Fab")
		)
		(fp_line
			(start -0.120396 0.3048)
			(end -0.120396 0.2794)
			(stroke
				(width 0.1)
				(type default)
			)
			(layer "B.Fab")
		)
		(fp_line
			(start 0.12065 0.3048)
			(end 0.67945 0.3048)
			(stroke
				(width 0.1)
				(type default)
			)
			(layer "B.Fab")
		)
		(fp_line
			(start 0.67945 0.3048)
			(end 0.67945 -0.305054)
			(stroke
				(width 0.1)
				(type default)
			)
			(layer "B.Fab")
		)
		(fp_line
			(start -0.120396 0.2794)
			(end 0.12065 0.2794)
			(stroke
				(width 0.1)
				(type default)
			)
			(layer "B.Fab")
		)
		(fp_line
			(start 0.12065 0.2794)
			(end 0.12065 0.3048)
			(stroke
				(width 0.1)
				(type default)
			)
			(layer "B.Fab")
		)
		(fp_line
			(start -0.12065 -0.2794)
			(end -0.12065 -0.3048)
			(stroke
				(width 0.1)
				(type default)
			)
			(layer "B.Fab")
		)
		(fp_line
			(start 0.12065 -0.2794)
			(end -0.12065 -0.2794)
			(stroke
				(width 0.1)
				(type default)
			)
			(layer "B.Fab")
		)
		(fp_line
			(start -0.67945 -0.3048)
			(end -0.67945 0.3048)
			(stroke
				(width 0.1)
				(type default)
			)
			(layer "B.Fab")
		)
		(fp_line
			(start -0.12065 -0.3048)
			(end -0.67945 -0.3048)
			(stroke
				(width 0.1)
				(type default)
			)
			(layer "B.Fab")
		)
		(fp_line
			(start 0.12065 -0.305054)
			(end 0.12065 -0.2794)
			(stroke
				(width 0.1)
				(type default)
			)
			(layer "B.Fab")
		)
		(fp_line
			(start 0.67945 -0.305054)
			(end 0.12065 -0.305054)
			(stroke
				(width 0.1)
				(type default)
			)
			(layer "B.Fab")
		)
		(pad "1" smd circle
			(at 0.40005 0 90)
			(size 0 0)
			(layers "B.Cu" "B.Mask" "B.Paste")
			(net "HSC_VDD_R")
		)
		(pad "2" smd circle
			(at -0.40005 0 90)
			(size 0 0)
			(layers "B.Cu" "B.Mask" "B.Paste")
			(net "AGND_HSC")
		)
	)
	(footprint ""
		(layer "B.Cu")
		(at 257.63982 -49.430686 180)
		(property "Reference" "PR4541"
			(at 0 0 0)
			(layer "B.SilkS")
			(hide yes)
			(effects
				(font
					(size 1.27 1.27)
				)
				(justify mirror)
			)
		)
		(property "Value" ""
			(at 0 0 0)
			(layer "B.Fab")
			(effects
				(font
					(size 1.27 1.27)
				)
				(justify mirror)
			)
		)
		(duplicate_pad_numbers_are_jumpers no)
		(fp_line
			(start 0.7874 0.4064)
			(end 0.7874 -0.4064)
			(stroke
				(width 0.1524)
				(type default)
			)
			(layer "B.SilkS")
		)
		(fp_line
			(start 0.7874 -0.4064)
			(end -0.7874 -0.4064)
			(stroke
				(width 0.1524)
				(type default)
			)
			(layer "B.SilkS")
		)
		(fp_line
			(start -0.7874 0.4064)
			(end 0.7874 0.4064)
			(stroke
				(width 0.1524)
				(type default)
			)
			(layer "B.SilkS")
		)
		(fp_line
			(start -0.7874 -0.4064)
			(end -0.7874 0.4064)
			(stroke
				(width 0.1524)
				(type default)
			)
			(layer "B.SilkS")
		)
		(fp_line
			(start 0.67945 0.3048)
			(end 0.67945 -0.305054)
			(stroke
				(width 0.1)
				(type default)
			)
			(layer "B.Fab")
		)
		(fp_line
			(start 0.67945 -0.305054)
			(end 0.12065 -0.305054)
			(stroke
				(width 0.1)
				(type default)
			)
			(layer "B.Fab")
		)
		(fp_line
			(start 0.12065 0.3048)
			(end 0.67945 0.3048)
			(stroke
				(width 0.1)
				(type default)
			)
			(layer "B.Fab")
		)
		(fp_line
			(start 0.12065 0.2794)
			(end 0.12065 0.3048)
			(stroke
				(width 0.1)
				(type default)
			)
			(layer "B.Fab")
		)
		(fp_line
			(start 0.12065 -0.2794)
			(end -0.12065 -0.2794)
			(stroke
				(width 0.1)
				(type default)
			)
			(layer "B.Fab")
		)
		(fp_line
			(start 0.12065 -0.305054)
			(end 0.12065 -0.2794)
			(stroke
				(width 0.1)
				(type default)
			)
			(layer "B.Fab")
		)
		(fp_line
			(start -0.120396 0.3048)
			(end -0.120396 0.2794)
			(stroke
				(width 0.1)
				(type default)
			)
			(layer "B.Fab")
		)
		(fp_line
			(start -0.120396 0.2794)
			(end 0.12065 0.2794)
			(stroke
				(width 0.1)
				(type default)
			)
			(layer "B.Fab")
		)
		(fp_line
			(start -0.12065 -0.2794)
			(end -0.12065 -0.3048)
			(stroke
				(width 0.1)
				(type default)
			)
			(layer "B.Fab")
		)
		(fp_line
			(start -0.12065 -0.3048)
			(end -0.67945 -0.3048)
			(stroke
				(width 0.1)
				(type default)
			)
			(layer "B.Fab")
		)
		(fp_line
			(start -0.67945 0.3048)
			(end -0.120396 0.3048)
			(stroke
				(width 0.1)
				(type default)
			)
			(layer "B.Fab")
		)
		(fp_line
			(start -0.67945 -0.3048)
			(end -0.67945 0.3048)
			(stroke
				(width 0.1)
				(type default)
			)
			(layer "B.Fab")
		)
		(pad "1" smd circle
			(at 0.40005 0)
			(size 0 0)
			(layers "B.Cu" "B.Mask" "B.Paste")
			(net "P12V_E1S_ISET_0")
		)
		(pad "2" smd circle
			(at -0.40005 0)
			(size 0 0)
			(layers "B.Cu" "B.Mask" "B.Paste")
			(net "P12V_E1S_ISET_0_R")
		)
	)
	(footprint ""
		(layer "B.Cu")
		(at 348.2467 -358.848914 180)
		(property "Reference" "R2377"
			(at 0 0 0)
			(layer "B.SilkS")
			(hide yes)
			(effects
				(font
					(size 1.27 1.27)
				)
				(justify mirror)
			)
		)
		(property "Value" ""
			(at 0 0 0)
			(layer "B.Fab")
			(effects
				(font
					(size 1.27 1.27)
				)
				(justify mirror)
			)
		)
		(duplicate_pad_numbers_are_jumpers no)
		(fp_line
			(start 0.7874 0.4064)
			(end 0.7874 -0.4064)
			(stroke
				(width 0.1524)
				(type default)
			)
			(layer "B.SilkS")
		)
		(fp_line
			(start 0.7874 -0.4064)
			(end -0.7874 -0.4064)
			(stroke
				(width 0.1524)
				(type default)
			)
			(layer "B.SilkS")
		)
		(fp_line
			(start -0.7874 0.4064)
			(end 0.7874 0.4064)
			(stroke
				(width 0.1524)
				(type default)
			)
			(layer "B.SilkS")
		)
		(fp_line
			(start -0.7874 -0.4064)
			(end -0.7874 0.4064)
			(stroke
				(width 0.1524)
				(type default)
			)
			(layer "B.SilkS")
		)
		(fp_line
			(start 0.67945 0.3048)
			(end 0.67945 -0.305054)
			(stroke
				(width 0.1)
				(type default)
			)
			(layer "B.Fab")
		)
		(fp_line
			(start 0.67945 -0.305054)
			(end 0.12065 -0.305054)
			(stroke
				(width 0.1)
				(type default)
			)
			(layer "B.Fab")
		)
		(fp_line
			(start 0.12065 0.3048)
			(end 0.67945 0.3048)
			(stroke
				(width 0.1)
				(type default)
			)
			(layer "B.Fab")
		)
		(fp_line
			(start 0.12065 0.2794)
			(end 0.12065 0.3048)
			(stroke
				(width 0.1)
				(type default)
			)
			(layer "B.Fab")
		)
		(fp_line
			(start 0.12065 -0.2794)
			(end -0.12065 -0.2794)
			(stroke
				(width 0.1)
				(type default)
			)
			(layer "B.Fab")
		)
		(fp_line
			(start 0.12065 -0.305054)
			(end 0.12065 -0.2794)
			(stroke
				(width 0.1)
				(type default)
			)
			(layer "B.Fab")
		)
		(fp_line
			(start -0.120396 0.3048)
			(end -0.120396 0.2794)
			(stroke
				(width 0.1)
				(type default)
			)
			(layer "B.Fab")
		)
		(fp_line
			(start -0.120396 0.2794)
			(end 0.12065 0.2794)
			(stroke
				(width 0.1)
				(type default)
			)
			(layer "B.Fab")
		)
		(fp_line
			(start -0.12065 -0.2794)
			(end -0.12065 -0.3048)
			(stroke
				(width 0.1)
				(type default)
			)
			(layer "B.Fab")
		)
		(fp_line
			(start -0.12065 -0.3048)
			(end -0.67945 -0.3048)
			(stroke
				(width 0.1)
				(type default)
			)
			(layer "B.Fab")
		)
		(fp_line
			(start -0.67945 0.3048)
			(end -0.120396 0.3048)
			(stroke
				(width 0.1)
				(type default)
			)
			(layer "B.Fab")
		)
		(fp_line
			(start -0.67945 -0.3048)
			(end -0.67945 0.3048)
			(stroke
				(width 0.1)
				(type default)
			)
			(layer "B.Fab")
		)
		(pad "1" smd circle
			(at 0.40005 0)
			(size 0 0)
			(layers "B.Cu" "B.Mask" "B.Paste")
			(net "P3V3_AUX")
		)
		(pad "2" smd circle
			(at -0.40005 0)
			(size 0 0)
			(layers "B.Cu" "B.Mask" "B.Paste")
			(net "PWRGD_PVCCFA_EHV_FIVRA_CPU0_R")
		)
	)
	(footprint ""
		(layer "B.Cu")
		(at 278.128984 -193.669666 -90)
		(property "Reference" "R253"
			(at 0 0 90)
			(layer "B.SilkS")
			(hide yes)
			(effects
				(font
					(size 1.27 1.27)
				)
				(justify mirror)
			)
		)
		(property "Value" ""
			(at 0 0 90)
			(layer "B.Fab")
			(effects
				(font
					(size 1.27 1.27)
				)
				(justify mirror)
			)
		)
		(duplicate_pad_numbers_are_jumpers no)
		(fp_line
			(start -0.7874 0.4064)
			(end 0.7874 0.4064)
			(stroke
				(width 0.1524)
				(type default)
			)
			(layer "B.SilkS")
		)
		(fp_line
			(start 0.7874 0.4064)
			(end 0.7874 -0.4064)
			(stroke
				(width 0.1524)
				(type default)
			)
			(layer "B.SilkS")
		)
		(fp_line
			(start -0.7874 -0.4064)
			(end -0.7874 0.4064)
			(stroke
				(width 0.1524)
				(type default)
			)
			(layer "B.SilkS")
		)
		(fp_line
			(start 0.7874 -0.4064)
			(end -0.7874 -0.4064)
			(stroke
				(width 0.1524)
				(type default)
			)
			(layer "B.SilkS")
		)
		(fp_line
			(start -0.67945 0.3048)
			(end -0.120396 0.3048)
			(stroke
				(width 0.1)
				(type default)
			)
			(layer "B.Fab")
		)
		(fp_line
			(start -0.120396 0.3048)
			(end -0.120396 0.2794)
			(stroke
				(width 0.1)
				(type default)
			)
			(layer "B.Fab")
		)
		(fp_line
			(start 0.12065 0.3048)
			(end 0.67945 0.3048)
			(stroke
				(width 0.1)
				(type default)
			)
			(layer "B.Fab")
		)
		(fp_line
			(start 0.67945 0.3048)
			(end 0.67945 -0.305054)
			(stroke
				(width 0.1)
				(type default)
			)
			(layer "B.Fab")
		)
		(fp_line
			(start -0.120396 0.2794)
			(end 0.12065 0.2794)
			(stroke
				(width 0.1)
				(type default)
			)
			(layer "B.Fab")
		)
		(fp_line
			(start 0.12065 0.2794)
			(end 0.12065 0.3048)
			(stroke
				(width 0.1)
				(type default)
			)
			(layer "B.Fab")
		)
		(fp_line
			(start -0.12065 -0.2794)
			(end -0.12065 -0.3048)
			(stroke
				(width 0.1)
				(type default)
			)
			(layer "B.Fab")
		)
		(fp_line
			(start 0.12065 -0.2794)
			(end -0.12065 -0.2794)
			(stroke
				(width 0.1)
				(type default)
			)
			(layer "B.Fab")
		)
		(fp_line
			(start -0.67945 -0.3048)
			(end -0.67945 0.3048)
			(stroke
				(width 0.1)
				(type default)
			)
			(layer "B.Fab")
		)
		(fp_line
			(start -0.12065 -0.3048)
			(end -0.67945 -0.3048)
			(stroke
				(width 0.1)
				(type default)
			)
			(layer "B.Fab")
		)
		(fp_line
			(start 0.12065 -0.305054)
			(end 0.12065 -0.2794)
			(stroke
				(width 0.1)
				(type default)
			)
			(layer "B.Fab")
		)
		(fp_line
			(start 0.67945 -0.305054)
			(end 0.12065 -0.305054)
			(stroke
				(width 0.1)
				(type default)
			)
			(layer "B.Fab")
		)
		(pad "1" smd circle
			(at 0.40005 0 90)
			(size 0 0)
			(layers "B.Cu" "B.Mask" "B.Paste")
			(net "PVNN_TERM_CPU0")
		)
		(pad "2" smd circle
			(at -0.40005 0 90)
			(size 0 0)
			(layers "B.Cu" "B.Mask" "B.Paste")
			(net "FM_S3M_CPU0_LVC1_GPIO_2")
		)
	)
)
